(kicad_pcb
	(version 20241229)
	(generator "pcbnew")
	(generator_version "9.0")
	(general
		(thickness 1.62)
		(legacy_teardrops no)
	)
	(paper "A4")
	(title_block
		(title "OCuLink to 10GbE adapter")
		(date "2026-02-23")
		(rev "1.1.0")
		(company "Antmicro Ltd")
		(comment 1 "www.antmicro.com")
		(comment 9 "footprints 363-367 of 510")
	)
	(layers
		(0 "F.Cu" signal)
		(4 "In1.Cu" signal)
		(6 "In2.Cu" signal)
		(8 "In3.Cu" signal)
		(10 "In4.Cu" signal)
		(12 "In5.Cu" signal)
		(14 "In6.Cu" signal)
		(2 "B.Cu" signal)
		(9 "F.Adhes" user "F.Adhesive")
		(11 "B.Adhes" user "B.Adhesive")
		(13 "F.Paste" user)
		(15 "B.Paste" user)
		(5 "F.SilkS" user "F.Silkscreen")
		(7 "B.SilkS" user "B.Silkscreen")
		(1 "F.Mask" user)
		(3 "B.Mask" user)
		(17 "Dwgs.User" user "User.Drawings")
		(19 "Cmts.User" user "User.Comments")
		(21 "Eco1.User" user "User.Eco1")
		(23 "Eco2.User" user "User.Eco2")
		(25 "Edge.Cuts" user)
		(27 "Margin" user)
		(31 "F.CrtYd" user "F.Courtyard")
		(29 "B.CrtYd" user "B.Courtyard")
		(35 "F.Fab" user)
		(33 "B.Fab" user)
	)
	(footprint "antmicro-footprints:C_0402_1005Metric"
		(layer "B.Cu")
		(at 90.225 98.3 90)
		(descr "Capacitor SMD 0402")
		(tags "capacitor SMD 0402")
		(property "Reference" "C132"
			(at 10.69 -0.445 90)
			(layer "B.SilkS")
			(effects
				(font
					(size 0.7 0.7)
					(thickness 0.15)
				)
				(justify right top mirror)
			)
		)
		(property "Value" "C_1u_25V_0402"
			(at -1.022927 -2.155213 90)
			(layer "B.Fab")
			(hide yes)
			(effects
				(font
					(size 0.7 0.7)
					(thickness 0.15)
				)
				(justify right top mirror)
			)
		)
		(property "Datasheet" "https://www.murata.com/products/productdetail?partno=GRM155R61E105KE11%23"
			(at 0 0 90)
			(layer "B.Fab")
			(hide yes)
			(effects
				(font
					(size 1.27 1.27)
					(thickness 0.15)
				)
				(justify mirror)
			)
		)
		(property "Description" "SMD Multilayer Ceramic Capacitor, 1 µF, 25 V, 0402 [1005 Metric], ± 10%, X5R, GRM Series"
			(at 0 0 90)
			(layer "B.Fab")
			(hide yes)
			(effects
				(font
					(size 1.27 1.27)
					(thickness 0.15)
				)
				(justify mirror)
			)
		)
		(property "MPN" "GRM155R61E105KE11J"
			(at 0 0 90)
			(unlocked yes)
			(layer "B.Fab")
			(hide yes)
			(effects
				(font
					(size 1 1)
					(thickness 0.15)
				)
				(justify mirror)
			)
		)
		(property "Manufacturer" "Murata"
			(at 0 0 90)
			(unlocked yes)
			(layer "B.Fab")
			(hide yes)
			(effects
				(font
					(size 1 1)
					(thickness 0.15)
				)
				(justify mirror)
			)
		)
		(property "License" "Apache-2.0"
			(at 0 0 90)
			(unlocked yes)
			(layer "B.Fab")
			(hide yes)
			(effects
				(font
					(size 1 1)
					(thickness 0.15)
				)
				(justify mirror)
			)
		)
		(property "Author" "Antmicro"
			(at 0 0 90)
			(unlocked yes)
			(layer "B.Fab")
			(hide yes)
			(effects
				(font
					(size 1 1)
					(thickness 0.15)
				)
				(justify mirror)
			)
		)
		(property "Val" "1u"
			(at 0 0 90)
			(unlocked yes)
			(layer "B.Fab")
			(hide yes)
			(effects
				(font
					(size 1 1)
					(thickness 0.15)
				)
				(justify mirror)
			)
		)
		(property "Voltage" "25V"
			(at 0 0 90)
			(unlocked yes)
			(layer "B.Fab")
			(hide yes)
			(effects
				(font
					(size 1 1)
					(thickness 0.15)
				)
				(justify mirror)
			)
		)
		(property "Dielectric" "X5R"
			(at 0 0 90)
			(unlocked yes)
			(layer "B.Fab")
			(hide yes)
			(effects
				(font
					(size 1 1)
					(thickness 0.15)
				)
				(justify mirror)
			)
		)
		(sheetname "/X710-AT2 power/")
		(sheetfile "x710-at2-power.kicad_sch")
		(attr smd)
		(fp_rect
			(start -0.925 0.47)
			(end 0.925 -0.47)
			(stroke
				(width 0.05)
				(type default)
			)
			(fill no)
			(layer "B.CrtYd")
		)
		(fp_line
			(start 0.504 -0.248)
			(end -0.494 -0.248)
			(stroke
				(width 0.15)
				(type solid)
			)
			(layer "B.Fab")
		)
		(fp_line
			(start -0.494 -0.248)
			(end -0.494 0.25)
			(stroke
				(width 0.15)
				(type solid)
			)
			(layer "B.Fab")
		)
		(fp_line
			(start 0.504 0.25)
			(end 0.504 -0.248)
			(stroke
				(width 0.15)
				(type solid)
			)
			(layer "B.Fab")
		)
		(fp_line
			(start -0.494 0.25)
			(end 0.504 0.25)
			(stroke
				(width 0.15)
				(type solid)
			)
			(layer "B.Fab")
		)
		(pad "1" smd roundrect
			(at -0.48 0 90)
			(size 0.59 0.64)
			(layers "B.Cu" "B.Mask" "B.Paste")
			(roundrect_rratio 0.25)
			(net 28 "GND")
			(pintype "passive")
		)
		(pad "2" smd roundrect
			(at 0.48 0 90)
			(size 0.59 0.64)
			(layers "B.Cu" "B.Mask" "B.Paste")
			(roundrect_rratio 0.25)
			(net 7 "+3V3")
			(pintype "passive")
		)
	)
	(footprint "antmicro-footprints:C_0402_1005Metric"
		(layer "B.Cu")
		(at 88.225 98.3 90)
		(descr "Capacitor SMD 0402")
		(tags "capacitor SMD 0402")
		(property "Reference" "C112"
			(at 10.69 -0.490714 90)
			(layer "B.SilkS")
			(effects
				(font
					(size 0.7 0.7)
					(thickness 0.15)
				)
				(justify right top mirror)
			)
		)
		(property "Value" "C_1u_25V_0402"
			(at -1.022927 -2.155213 90)
			(layer "B.Fab")
			(hide yes)
			(effects
				(font
					(size 0.7 0.7)
					(thickness 0.15)
				)
				(justify right top mirror)
			)
		)
		(property "Datasheet" "https://www.murata.com/products/productdetail?partno=GRM155R61E105KE11%23"
			(at 0 0 90)
			(layer "B.Fab")
			(hide yes)
			(effects
				(font
					(size 1.27 1.27)
					(thickness 0.15)
				)
				(justify mirror)
			)
		)
		(property "Description" "SMD Multilayer Ceramic Capacitor, 1 µF, 25 V, 0402 [1005 Metric], ± 10%, X5R, GRM Series"
			(at 0 0 90)
			(layer "B.Fab")
			(hide yes)
			(effects
				(font
					(size 1.27 1.27)
					(thickness 0.15)
				)
				(justify mirror)
			)
		)
		(property "MPN" "GRM155R61E105KE11J"
			(at 0 0 90)
			(unlocked yes)
			(layer "B.Fab")
			(hide yes)
			(effects
				(font
					(size 1 1)
					(thickness 0.15)
				)
				(justify mirror)
			)
		)
		(property "Manufacturer" "Murata"
			(at 0 0 90)
			(unlocked yes)
			(layer "B.Fab")
			(hide yes)
			(effects
				(font
					(size 1 1)
					(thickness 0.15)
				)
				(justify mirror)
			)
		)
		(property "License" "Apache-2.0"
			(at 0 0 90)
			(unlocked yes)
			(layer "B.Fab")
			(hide yes)
			(effects
				(font
					(size 1 1)
					(thickness 0.15)
				)
				(justify mirror)
			)
		)
		(property "Author" "Antmicro"
			(at 0 0 90)
			(unlocked yes)
			(layer "B.Fab")
			(hide yes)
			(effects
				(font
					(size 1 1)
					(thickness 0.15)
				)
				(justify mirror)
			)
		)
		(property "Val" "1u"
			(at 0 0 90)
			(unlocked yes)
			(layer "B.Fab")
			(hide yes)
			(effects
				(font
					(size 1 1)
					(thickness 0.15)
				)
				(justify mirror)
			)
		)
		(property "Voltage" "25V"
			(at 0 0 90)
			(unlocked yes)
			(layer "B.Fab")
			(hide yes)
			(effects
				(font
					(size 1 1)
					(thickness 0.15)
				)
				(justify mirror)
			)
		)
		(property "Dielectric" "X5R"
			(at 0 0 90)
			(unlocked yes)
			(layer "B.Fab")
			(hide yes)
			(effects
				(font
					(size 1 1)
					(thickness 0.15)
				)
				(justify mirror)
			)
		)
		(sheetname "/X710-AT2 power/")
		(sheetfile "x710-at2-power.kicad_sch")
		(attr smd)
		(fp_rect
			(start -0.925 0.47)
			(end 0.925 -0.47)
			(stroke
				(width 0.05)
				(type default)
			)
			(fill no)
			(layer "B.CrtYd")
		)
		(fp_line
			(start 0.504 -0.248)
			(end -0.494 -0.248)
			(stroke
				(width 0.15)
				(type solid)
			)
			(layer "B.Fab")
		)
		(fp_line
			(start -0.494 -0.248)
			(end -0.494 0.25)
			(stroke
				(width 0.15)
				(type solid)
			)
			(layer "B.Fab")
		)
		(fp_line
			(start 0.504 0.25)
			(end 0.504 -0.248)
			(stroke
				(width 0.15)
				(type solid)
			)
			(layer "B.Fab")
		)
		(fp_line
			(start -0.494 0.25)
			(end 0.504 0.25)
			(stroke
				(width 0.15)
				(type solid)
			)
			(layer "B.Fab")
		)
		(pad "1" smd roundrect
			(at -0.48 0 90)
			(size 0.59 0.64)
			(layers "B.Cu" "B.Mask" "B.Paste")
			(roundrect_rratio 0.25)
			(net 28 "GND")
			(pintype "passive")
		)
		(pad "2" smd roundrect
			(at 0.48 0 90)
			(size 0.59 0.64)
			(layers "B.Cu" "B.Mask" "B.Paste")
			(roundrect_rratio 0.25)
			(net 9 "VCCD")
			(pintype "passive")
		)
	)
	(footprint "antmicro-footprints:R_0402_1005Metric"
		(layer "B.Cu")
		(at 76.48 145.34 90)
		(descr "Resistor SMD 0402")
		(tags "resistor SMD 0402")
		(property "Reference" "R36"
			(at 0.74 -0.35 90)
			(layer "B.SilkS")
			(effects
				(font
					(size 0.7 0.7)
					(thickness 0.15)
				)
				(justify right top mirror)
			)
		)
		(property "Value" "R_220R_0402"
			(at -1.011843 -1.772046 90)
			(layer "B.Fab")
			(hide yes)
			(effects
				(font
					(size 0.7 0.7)
					(thickness 0.15)
				)
				(justify right top mirror)
			)
		)
		(property "Datasheet" "https://www.bourns.com/docs/product-datasheets/cr.pdf"
			(at 0 0 90)
			(layer "B.Fab")
			(hide yes)
			(effects
				(font
					(size 1.27 1.27)
					(thickness 0.15)
				)
				(justify mirror)
			)
		)
		(property "Description" "SMD Chip Resistor, 220 ohm, ± 1%, 62.5 mW, 0402 [1005 Metric], Thick Film, General Purpose"
			(at 0 0 90)
			(layer "B.Fab")
			(hide yes)
			(effects
				(font
					(size 1.27 1.27)
					(thickness 0.15)
				)
				(justify mirror)
			)
		)
		(property "MPN" "CR0402-FX-2200GLF"
			(at 0 0 90)
			(unlocked yes)
			(layer "B.Fab")
			(hide yes)
			(effects
				(font
					(size 1 1)
					(thickness 0.15)
				)
				(justify mirror)
			)
		)
		(property "Manufacturer" "Bourns"
			(at 0 0 90)
			(unlocked yes)
			(layer "B.Fab")
			(hide yes)
			(effects
				(font
					(size 1 1)
					(thickness 0.15)
				)
				(justify mirror)
			)
		)
		(property "License" "Apache-2.0"
			(at 0 0 90)
			(unlocked yes)
			(layer "B.Fab")
			(hide yes)
			(effects
				(font
					(size 1 1)
					(thickness 0.15)
				)
				(justify mirror)
			)
		)
		(property "Author" "Antmicro"
			(at 0 0 90)
			(unlocked yes)
			(layer "B.Fab")
			(hide yes)
			(effects
				(font
					(size 1 1)
					(thickness 0.15)
				)
				(justify mirror)
			)
		)
		(property "Val" "220R"
			(at 0 0 90)
			(unlocked yes)
			(layer "B.Fab")
			(hide yes)
			(effects
				(font
					(size 1 1)
					(thickness 0.15)
				)
				(justify mirror)
			)
		)
		(property "Tolerance" "1%"
			(at 0 0 90)
			(unlocked yes)
			(layer "B.Fab")
			(hide yes)
			(effects
				(font
					(size 1 1)
					(thickness 0.15)
				)
				(justify mirror)
			)
		)
		(sheetname "/2xRJ45/")
		(sheetfile "2xrj45.kicad_sch")
		(attr smd)
		(fp_rect
			(start -0.925 0.47)
			(end 0.925 -0.47)
			(stroke
				(width 0.05)
				(type default)
			)
			(fill no)
			(layer "B.CrtYd")
		)
		(fp_rect
			(start -0.5 0.25)
			(end 0.5 -0.25)
			(stroke
				(width 0.15)
				(type solid)
			)
			(fill no)
			(layer "B.Fab")
		)
		(pad "1" smd roundrect
			(at -0.48 0 90)
			(size 0.59 0.64)
			(layers "B.Cu" "B.Mask" "B.Paste")
			(roundrect_rratio 0.25)
			(net 52 "Net-(J3-LED_YG_Y-)")
			(pintype "passive")
		)
		(pad "2" smd roundrect
			(at 0.48 0 90)
			(size 0.59 0.64)
			(layers "B.Cu" "B.Mask" "B.Paste")
			(roundrect_rratio 0.25)
			(net 291 "/2xRJ45/~{P0_LINK_LESS_THAN_10G}")
			(pintype "passive")
		)
	)
	(footprint "antmicro-footprints:C_0402_1005Metric"
		(layer "B.Cu")
		(at 85.225 98.3 90)
		(descr "Capacitor SMD 0402")
		(tags "capacitor SMD 0402")
		(property "Reference" "C118"
			(at 10.69 -0.559286 90)
			(layer "B.SilkS")
			(effects
				(font
					(size 0.7 0.7)
					(thickness 0.15)
				)
				(justify right top mirror)
			)
		)
		(property "Value" "C_1u_25V_0402"
			(at -1.022927 -2.155213 90)
			(layer "B.Fab")
			(hide yes)
			(effects
				(font
					(size 0.7 0.7)
					(thickness 0.15)
				)
				(justify right top mirror)
			)
		)
		(property "Datasheet" "https://www.murata.com/products/productdetail?partno=GRM155R61E105KE11%23"
			(at 0 0 90)
			(layer "B.Fab")
			(hide yes)
			(effects
				(font
					(size 1.27 1.27)
					(thickness 0.15)
				)
				(justify mirror)
			)
		)
		(property "Description" "SMD Multilayer Ceramic Capacitor, 1 µF, 25 V, 0402 [1005 Metric], ± 10%, X5R, GRM Series"
			(at 0 0 90)
			(layer "B.Fab")
			(hide yes)
			(effects
				(font
					(size 1.27 1.27)
					(thickness 0.15)
				)
				(justify mirror)
			)
		)
		(property "MPN" "GRM155R61E105KE11J"
			(at 0 0 90)
			(unlocked yes)
			(layer "B.Fab")
			(hide yes)
			(effects
				(font
					(size 1 1)
					(thickness 0.15)
				)
				(justify mirror)
			)
		)
		(property "Manufacturer" "Murata"
			(at 0 0 90)
			(unlocked yes)
			(layer "B.Fab")
			(hide yes)
			(effects
				(font
					(size 1 1)
					(thickness 0.15)
				)
				(justify mirror)
			)
		)
		(property "License" "Apache-2.0"
			(at 0 0 90)
			(unlocked yes)
			(layer "B.Fab")
			(hide yes)
			(effects
				(font
					(size 1 1)
					(thickness 0.15)
				)
				(justify mirror)
			)
		)
		(property "Author" "Antmicro"
			(at 0 0 90)
			(unlocked yes)
			(layer "B.Fab")
			(hide yes)
			(effects
				(font
					(size 1 1)
					(thickness 0.15)
				)
				(justify mirror)
			)
		)
		(property "Val" "1u"
			(at 0 0 90)
			(unlocked yes)
			(layer "B.Fab")
			(hide yes)
			(effects
				(font
					(size 1 1)
					(thickness 0.15)
				)
				(justify mirror)
			)
		)
		(property "Voltage" "25V"
			(at 0 0 90)
			(unlocked yes)
			(layer "B.Fab")
			(hide yes)
			(effects
				(font
					(size 1 1)
					(thickness 0.15)
				)
				(justify mirror)
			)
		)
		(property "Dielectric" "X5R"
			(at 0 0 90)
			(unlocked yes)
			(layer "B.Fab")
			(hide yes)
			(effects
				(font
					(size 1 1)
					(thickness 0.15)
				)
				(justify mirror)
			)
		)
		(sheetname "/X710-AT2 power/")
		(sheetfile "x710-at2-power.kicad_sch")
		(attr smd)
		(fp_rect
			(start -0.925 0.47)
			(end 0.925 -0.47)
			(stroke
				(width 0.05)
				(type default)
			)
			(fill no)
			(layer "B.CrtYd")
		)
		(fp_line
			(start 0.504 -0.248)
			(end -0.494 -0.248)
			(stroke
				(width 0.15)
				(type solid)
			)
			(layer "B.Fab")
		)
		(fp_line
			(start -0.494 -0.248)
			(end -0.494 0.25)
			(stroke
				(width 0.15)
				(type solid)
			)
			(layer "B.Fab")
		)
		(fp_line
			(start 0.504 0.25)
			(end 0.504 -0.248)
			(stroke
				(width 0.15)
				(type solid)
			)
			(layer "B.Fab")
		)
		(fp_line
			(start -0.494 0.25)
			(end 0.504 0.25)
			(stroke
				(width 0.15)
				(type solid)
			)
			(layer "B.Fab")
		)
		(pad "1" smd roundrect
			(at -0.48 0 90)
			(size 0.59 0.64)
			(layers "B.Cu" "B.Mask" "B.Paste")
			(roundrect_rratio 0.25)
			(net 28 "GND")
			(pintype "passive")
		)
		(pad "2" smd roundrect
			(at 0.48 0 90)
			(size 0.59 0.64)
			(layers "B.Cu" "B.Mask" "B.Paste")
			(roundrect_rratio 0.25)
			(net 9 "VCCD")
			(pintype "passive")
		)
	)
	(footprint "antmicro-footprints:C_0402_1005Metric"
		(layer "B.Cu")
		(at 90.225 96.45 90)
		(descr "Capacitor SMD 0402")
		(tags "capacitor SMD 0402")
		(property "Reference" "C109"
			(at 11.58 -0.432343 90)
			(layer "B.SilkS")
			(effects
				(font
					(size 0.7 0.7)
					(thickness 0.15)
				)
				(justify right top mirror)
			)
		)
		(property "Value" "C_1u_25V_0402"
			(at -1.022927 -2.155213 90)
			(layer "B.Fab")
			(hide yes)
			(effects
				(font
					(size 0.7 0.7)
					(thickness 0.15)
				)
				(justify right top mirror)
			)
		)
		(property "Datasheet" "https://www.murata.com/products/productdetail?partno=GRM155R61E105KE11%23"
			(at 0 0 90)
			(layer "B.Fab")
			(hide yes)
			(effects
				(font
					(size 1.27 1.27)
					(thickness 0.15)
				)
				(justify mirror)
			)
		)
		(property "Description" "SMD Multilayer Ceramic Capacitor, 1 µF, 25 V, 0402 [1005 Metric], ± 10%, X5R, GRM Series"
			(at 0 0 90)
			(layer "B.Fab")
			(hide yes)
			(effects
				(font
					(size 1.27 1.27)
					(thickness 0.15)
				)
				(justify mirror)
			)
		)
		(property "MPN" "GRM155R61E105KE11J"
			(at 0 0 90)
			(unlocked yes)
			(layer "B.Fab")
			(hide yes)
			(effects
				(font
					(size 1 1)
					(thickness 0.15)
				)
				(justify mirror)
			)
		)
		(property "Manufacturer" "Murata"
			(at 0 0 90)
			(unlocked yes)
			(layer "B.Fab")
			(hide yes)
			(effects
				(font
					(size 1 1)
					(thickness 0.15)
				)
				(justify mirror)
			)
		)
		(property "License" "Apache-2.0"
			(at 0 0 90)
			(unlocked yes)
			(layer "B.Fab")
			(hide yes)
			(effects
				(font
					(size 1 1)
					(thickness 0.15)
				)
				(justify mirror)
			)
		)
		(property "Author" "Antmicro"
			(at 0 0 90)
			(unlocked yes)
			(layer "B.Fab")
			(hide yes)
			(effects
				(font
					(size 1 1)
					(thickness 0.15)
				)
				(justify mirror)
			)
		)
		(property "Val" "1u"
			(at 0 0 90)
			(unlocked yes)
			(layer "B.Fab")
			(hide yes)
			(effects
				(font
					(size 1 1)
					(thickness 0.15)
				)
				(justify mirror)
			)
		)
		(property "Voltage" "25V"
			(at 0 0 90)
			(unlocked yes)
			(layer "B.Fab")
			(hide yes)
			(effects
				(font
					(size 1 1)
					(thickness 0.15)
				)
				(justify mirror)
			)
		)
		(property "Dielectric" "X5R"
			(at 0 0 90)
			(unlocked yes)
			(layer "B.Fab")
			(hide yes)
			(effects
				(font
					(size 1 1)
					(thickness 0.15)
				)
				(justify mirror)
			)
		)
		(sheetname "/X710-AT2 power/")
		(sheetfile "x710-at2-power.kicad_sch")
		(attr smd)
		(fp_rect
			(start -0.925 0.47)
			(end 0.925 -0.47)
			(stroke
				(width 0.05)
				(type default)
			)
			(fill no)
			(layer "B.CrtYd")
		)
		(fp_line
			(start 0.504 -0.248)
			(end -0.494 -0.248)
			(stroke
				(width 0.15)
				(type solid)
			)
			(layer "B.Fab")
		)
		(fp_line
			(start -0.494 -0.248)
			(end -0.494 0.25)
			(stroke
				(width 0.15)
				(type solid)
			)
			(layer "B.Fab")
		)
		(fp_line
			(start 0.504 0.25)
			(end 0.504 -0.248)
			(stroke
				(width 0.15)
				(type solid)
			)
			(layer "B.Fab")
		)
		(fp_line
			(start -0.494 0.25)
			(end 0.504 0.25)
			(stroke
				(width 0.15)
				(type solid)
			)
			(layer "B.Fab")
		)
		(pad "1" smd roundrect
			(at -0.48 0 90)
			(size 0.59 0.64)
			(layers "B.Cu" "B.Mask" "B.Paste")
			(roundrect_rratio 0.25)
			(net 28 "GND")
			(pintype "passive")
		)
		(pad "2" smd roundrect
			(at 0.48 0 90)
			(size 0.59 0.64)
			(layers "B.Cu" "B.Mask" "B.Paste")
			(roundrect_rratio 0.25)
			(net 9 "VCCD")
			(pintype "passive")
		)
	)
)
